# S9S_MB_2U (Grand Teton) — schematic netlist excerpt (pin names and nets, part order shuffled) for the footprints in the layout excerpt that follows; sources: Cadence DE-HDL packaged netlist, KiCad conversion of 03242023_DA0F0TMBIJ0_F0T_Motherboard_J_brd_V01_OCP.brd

PR105  Q_RES  28K 1% EMPTY  pkg 0402LF  page 274 : A = PVCCINFAON_CPU0_VREF ; B = PVCCINFAON_CPU0_ADDR
C494  Q_CAP  47UF 4V 20% X6S  pkg C0805  page 76 : A = PVCCFA_EHV_FIVRA_CPU0 ; B = GND
R303  Q_RES  301 1% CHIP  pkg 0402LF  page 118 : A = PVNN_TERM_CPU1 ; B = H_CPU_RMCA_LVC1_R_N

(kicad_pcb
	(version 20260206)
	(generator "pcbnew")
	(generator_version "10.0")
	(general
		(thickness 1.6)
		(legacy_teardrops no)
	)
	(paper "A4")
	(title_block
		(title "03242023_DA0F0TMBIJ0_F0T_Motherboard_J_brd_V01_OCP.brd")
		(comment 1 "Grand Teton / footprints 4931-4933 of 6105")
	)
	(layers
		(0 "F.Cu" signal "TOP")
		(4 "In1.Cu" signal "GND")
		(6 "In2.Cu" signal "IN1")
		(8 "In3.Cu" signal "GND1")
		(10 "In4.Cu" signal "IN2")
		(12 "In5.Cu" signal "GND2")
		(14 "In6.Cu" signal "IN3")
		(16 "In7.Cu" signal "GND3")
		(18 "In8.Cu" signal "VCC")
		(20 "In9.Cu" signal "VCC1")
		(22 "In10.Cu" signal "GND4")
		(24 "In11.Cu" signal "IN4")
		(26 "In12.Cu" signal "GND5")
		(28 "In13.Cu" signal "IN5")
		(30 "In14.Cu" signal "GND6")
		(32 "In15.Cu" signal "IN6")
		(34 "In16.Cu" signal "GND7")
		(2 "B.Cu" signal "BOTTOM")
		(9 "F.Adhes" user "F.Adhesive")
		(11 "B.Adhes" user "B.Adhesive")
		(13 "F.Paste" user "Package Geometry/Pastemask Top")
		(15 "B.Paste" user "Package Geometry/Pastemask Bottom")
		(5 "F.SilkS" user "Ref Des/Silkscreen Top")
		(7 "B.SilkS" user "Ref Des/Silkscreen Bottom")
		(1 "F.Mask" user "Board Geometry/Soldermask Top")
		(3 "B.Mask" user "Board Geometry/Soldermask Bottom")
		(17 "Dwgs.User" user "User.Drawings")
		(19 "Cmts.User" user "User.Comments")
		(21 "Eco1.User" user "User.Eco1")
		(23 "Eco2.User" user "User.Eco2")
		(25 "Edge.Cuts" user "Board Geometry/Outline")
		(27 "Margin" user)
		(31 "F.CrtYd" user "Package Geometry/Place Bound Top")
		(29 "B.CrtYd" user "Package Geometry/Place Bound Bottom")
		(35 "F.Fab" user "Ref Des/Assembly Top")
		(33 "B.Fab" user "Ref Des/Assembly Bottom")
	)
	(footprint ""
		(layer "B.Cu")
		(at 85.122004 -186.003692 -90)
		(property "Reference" "R303"
			(at 0 0 90)
			(layer "B.SilkS")
			(hide yes)
			(effects
				(font
					(size 1.27 1.27)
				)
				(justify mirror)
			)
		)
		(property "Value" ""
			(at 0 0 90)
			(layer "B.Fab")
			(effects
				(font
					(size 1.27 1.27)
				)
				(justify mirror)
			)
		)
		(duplicate_pad_numbers_are_jumpers no)
		(fp_line
			(start -0.7874 0.4064)
			(end 0.7874 0.4064)
			(stroke
				(width 0.1524)
				(type default)
			)
			(layer "B.SilkS")
		)
		(fp_line
			(start 0.7874 0.4064)
			(end 0.7874 -0.4064)
			(stroke
				(width 0.1524)
				(type default)
			)
			(layer "B.SilkS")
		)
		(fp_line
			(start -0.7874 -0.4064)
			(end -0.7874 0.4064)
			(stroke
				(width 0.1524)
				(type default)
			)
			(layer "B.SilkS")
		)
		(fp_line
			(start 0.7874 -0.4064)
			(end -0.7874 -0.4064)
			(stroke
				(width 0.1524)
				(type default)
			)
			(layer "B.SilkS")
		)
		(fp_line
			(start -0.67945 0.3048)
			(end -0.120396 0.3048)
			(stroke
				(width 0.1)
				(type default)
			)
			(layer "B.Fab")
		)
		(fp_line
			(start -0.120396 0.3048)
			(end -0.120396 0.2794)
			(stroke
				(width 0.1)
				(type default)
			)
			(layer "B.Fab")
		)
		(fp_line
			(start 0.12065 0.3048)
			(end 0.67945 0.3048)
			(stroke
				(width 0.1)
				(type default)
			)
			(layer "B.Fab")
		)
		(fp_line
			(start 0.67945 0.3048)
			(end 0.67945 -0.305054)
			(stroke
				(width 0.1)
				(type default)
			)
			(layer "B.Fab")
		)
		(fp_line
			(start -0.120396 0.2794)
			(end 0.12065 0.2794)
			(stroke
				(width 0.1)
				(type default)
			)
			(layer "B.Fab")
		)
		(fp_line
			(start 0.12065 0.2794)
			(end 0.12065 0.3048)
			(stroke
				(width 0.1)
				(type default)
			)
			(layer "B.Fab")
		)
		(fp_line
			(start -0.12065 -0.2794)
			(end -0.12065 -0.3048)
			(stroke
				(width 0.1)
				(type default)
			)
			(layer "B.Fab")
		)
		(fp_line
			(start 0.12065 -0.2794)
			(end -0.12065 -0.2794)
			(stroke
				(width 0.1)
				(type default)
			)
			(layer "B.Fab")
		)
		(fp_line
			(start -0.67945 -0.3048)
			(end -0.67945 0.3048)
			(stroke
				(width 0.1)
				(type default)
			)
			(layer "B.Fab")
		)
		(fp_line
			(start -0.12065 -0.3048)
			(end -0.67945 -0.3048)
			(stroke
				(width 0.1)
				(type default)
			)
			(layer "B.Fab")
		)
		(fp_line
			(start 0.12065 -0.305054)
			(end 0.12065 -0.2794)
			(stroke
				(width 0.1)
				(type default)
			)
			(layer "B.Fab")
		)
		(fp_line
			(start 0.67945 -0.305054)
			(end 0.12065 -0.305054)
			(stroke
				(width 0.1)
				(type default)
			)
			(layer "B.Fab")
		)
		(pad "1" smd circle
			(at 0.40005 0 90)
			(size 0 0)
			(layers "B.Cu" "B.Mask" "B.Paste")
			(net "PVNN_TERM_CPU1")
		)
		(pad "2" smd circle
			(at -0.40005 0 90)
			(size 0 0)
			(layers "B.Cu" "B.Mask" "B.Paste")
			(net "H_CPU_RMCA_LVC1_R_N")
		)
	)
	(footprint ""
		(layer "B.Cu")
		(at 406.776428 -257.89001 -90)
		(property "Reference" "C494"
			(at 0 0 90)
			(layer "B.SilkS")
			(hide yes)
			(effects
				(font
					(size 1.27 1.27)
				)
				(justify mirror)
			)
		)
		(property "Value" ""
			(at 0 0 90)
			(layer "B.Fab")
			(effects
				(font
					(size 1.27 1.27)
				)
				(justify mirror)
			)
		)
		(duplicate_pad_numbers_are_jumpers no)
		(fp_line
			(start -1.524 0.762)
			(end 1.524 0.762)
			(stroke
				(width 0.1524)
				(type default)
			)
			(layer "B.SilkS")
		)
		(fp_line
			(start 1.524 0.762)
			(end 1.524 -0.762)
			(stroke
				(width 0.1524)
				(type default)
			)
			(layer "B.SilkS")
		)
		(fp_line
			(start -1.524 -0.762)
			(end -1.524 0.762)
			(stroke
				(width 0.1524)
				(type default)
			)
			(layer "B.SilkS")
		)
		(fp_line
			(start 1.524 -0.762)
			(end -1.524 -0.762)
			(stroke
				(width 0.1524)
				(type default)
			)
			(layer "B.SilkS")
		)
		(fp_line
			(start -1.1049 0.724916)
			(end -1.1049 -0.724916)
			(stroke
				(width 0.1)
				(type default)
			)
			(layer "B.Fab")
		)
		(fp_line
			(start 1.1049 0.724916)
			(end -1.1049 0.724916)
			(stroke
				(width 0.1)
				(type default)
			)
			(layer "B.Fab")
		)
		(fp_line
			(start -1.1049 -0.724916)
			(end 1.1049 -0.724916)
			(stroke
				(width 0.1)
				(type default)
			)
			(layer "B.Fab")
		)
		(fp_line
			(start 1.1049 -0.724916)
			(end 1.1049 0.724916)
			(stroke
				(width 0.1)
				(type default)
			)
			(layer "B.Fab")
		)
		(pad "1" smd rect
			(at 0.889 0 270)
			(size 1.016 1.27)
			(layers "B.Cu" "B.Mask" "B.Paste")
			(net "PVCCFA_EHV_FIVRA_CPU0")
		)
		(pad "2" smd rect
			(at -0.889 0 270)
			(size 1.016 1.27)
			(layers "B.Cu" "B.Mask" "B.Paste")
			(net "GND")
		)
	)
	(footprint ""
		(layer "B.Cu")
		(at 420.682166 -138.333988 180)
		(property "Reference" "PR105"
			(at 0 0 0)
			(layer "B.SilkS")
			(hide yes)
			(effects
				(font
					(size 1.27 1.27)
				)
				(justify mirror)
			)
		)
		(property "Value" ""
			(at 0 0 0)
			(layer "B.Fab")
			(effects
				(font
					(size 1.27 1.27)
				)
				(justify mirror)
			)
		)
		(duplicate_pad_numbers_are_jumpers no)
		(fp_line
			(start 0.7874 0.4064)
			(end 0.7874 -0.4064)
			(stroke
				(width 0.1524)
				(type default)
			)
			(layer "B.SilkS")
		)
		(fp_line
			(start 0.7874 -0.4064)
			(end -0.7874 -0.4064)
			(stroke
				(width 0.1524)
				(type default)
			)
			(layer "B.SilkS")
		)
		(fp_line
			(start -0.7874 0.4064)
			(end 0.7874 0.4064)
			(stroke
				(width 0.1524)
				(type default)
			)
			(layer "B.SilkS")
		)
		(fp_line
			(start -0.7874 -0.4064)
			(end -0.7874 0.4064)
			(stroke
				(width 0.1524)
				(type default)
			)
			(layer "B.SilkS")
		)
		(fp_line
			(start 0.67945 0.3048)
			(end 0.67945 -0.305054)
			(stroke
				(width 0.1)
				(type default)
			)
			(layer "B.Fab")
		)
		(fp_line
			(start 0.67945 -0.305054)
			(end 0.12065 -0.305054)
			(stroke
				(width 0.1)
				(type default)
			)
			(layer "B.Fab")
		)
		(fp_line
			(start 0.12065 0.3048)
			(end 0.67945 0.3048)
			(stroke
				(width 0.1)
				(type default)
			)
			(layer "B.Fab")
		)
		(fp_line
			(start 0.12065 0.2794)
			(end 0.12065 0.3048)
			(stroke
				(width 0.1)
				(type default)
			)
			(layer "B.Fab")
		)
		(fp_line
			(start 0.12065 -0.2794)
			(end -0.12065 -0.2794)
			(stroke
				(width 0.1)
				(type default)
			)
			(layer "B.Fab")
		)
		(fp_line
			(start 0.12065 -0.305054)
			(end 0.12065 -0.2794)
			(stroke
				(width 0.1)
				(type default)
			)
			(layer "B.Fab")
		)
		(fp_line
			(start -0.120396 0.3048)
			(end -0.120396 0.2794)
			(stroke
				(width 0.1)
				(type default)
			)
			(layer "B.Fab")
		)
		(fp_line
			(start -0.120396 0.2794)
			(end 0.12065 0.2794)
			(stroke
				(width 0.1)
				(type default)
			)
			(layer "B.Fab")
		)
		(fp_line
			(start -0.12065 -0.2794)
			(end -0.12065 -0.3048)
			(stroke
				(width 0.1)
				(type default)
			)
			(layer "B.Fab")
		)
		(fp_line
			(start -0.12065 -0.3048)
			(end -0.67945 -0.3048)
			(stroke
				(width 0.1)
				(type default)
			)
			(layer "B.Fab")
		)
		(fp_line
			(start -0.67945 0.3048)
			(end -0.120396 0.3048)
			(stroke
				(width 0.1)
				(type default)
			)
			(layer "B.Fab")
		)
		(fp_line
			(start -0.67945 -0.3048)
			(end -0.67945 0.3048)
			(stroke
				(width 0.1)
				(type default)
			)
			(layer "B.Fab")
		)
		(pad "1" smd circle
			(at 0.40005 0)
			(size 0 0)
			(layers "B.Cu" "B.Mask" "B.Paste")
			(net "PVCCINFAON_CPU0_VREF")
		)
		(pad "2" smd circle
			(at -0.40005 0)
			(size 0 0)
			(layers "B.Cu" "B.Mask" "B.Paste")
			(net "PVCCINFAON_CPU0_ADDR")
		)
	)
)
